(kicad_pcb
	(version 20260206)
	(generator "pcbnew")
	(generator_version "10.0")
	(general
		(thickness 1.6)
		(legacy_teardrops no)
	)
	(paper "A4")
	(title_block
		(title "03242023_DA0F0TMBIJ0_F0T_Motherboard_J_brd_V01_OCP.brd")
		(comment 1 "Grand Teton / footprints 5608-5613 of 6105")
	)
	(layers
		(0 "F.Cu" signal "TOP")
		(4 "In1.Cu" signal "GND")
		(6 "In2.Cu" signal "IN1")
		(8 "In3.Cu" signal "GND1")
		(10 "In4.Cu" signal "IN2")
		(12 "In5.Cu" signal "GND2")
		(14 "In6.Cu" signal "IN3")
		(16 "In7.Cu" signal "GND3")
		(18 "In8.Cu" signal "VCC")
		(20 "In9.Cu" signal "VCC1")
		(22 "In10.Cu" signal "GND4")
		(24 "In11.Cu" signal "IN4")
		(26 "In12.Cu" signal "GND5")
		(28 "In13.Cu" signal "IN5")
		(30 "In14.Cu" signal "GND6")
		(32 "In15.Cu" signal "IN6")
		(34 "In16.Cu" signal "GND7")
		(2 "B.Cu" signal "BOTTOM")
		(9 "F.Adhes" user "F.Adhesive")
		(11 "B.Adhes" user "B.Adhesive")
		(13 "F.Paste" user "Package Geometry/Pastemask Top")
		(15 "B.Paste" user "Package Geometry/Pastemask Bottom")
		(5 "F.SilkS" user "Ref Des/Silkscreen Top")
		(7 "B.SilkS" user "Ref Des/Silkscreen Bottom")
		(1 "F.Mask" user "Board Geometry/Soldermask Top")
		(3 "B.Mask" user "Board Geometry/Soldermask Bottom")
		(17 "Dwgs.User" user "User.Drawings")
		(19 "Cmts.User" user "User.Comments")
		(21 "Eco1.User" user "User.Eco1")
		(23 "Eco2.User" user "User.Eco2")
		(25 "Edge.Cuts" user "Board Geometry/Outline")
		(27 "Margin" user)
		(31 "F.CrtYd" user "Package Geometry/Place Bound Top")
		(29 "B.CrtYd" user "Package Geometry/Place Bound Bottom")
		(35 "F.Fab" user "Ref Des/Assembly Top")
		(33 "B.Fab" user "Ref Des/Assembly Bottom")
	)
	(footprint ""
		(layer "B.Cu")
		(at 267.652246 -193.503296 -90)
		(property "Reference" "R707"
			(at 0 0 90)
			(layer "B.SilkS")
			(hide yes)
			(effects
				(font
					(size 1.27 1.27)
				)
				(justify mirror)
			)
		)
		(property "Value" ""
			(at 0 0 90)
			(layer "B.Fab")
			(effects
				(font
					(size 1.27 1.27)
				)
				(justify mirror)
			)
		)
		(duplicate_pad_numbers_are_jumpers no)
		(fp_line
			(start -0.7874 0.4064)
			(end 0.7874 0.4064)
			(stroke
				(width 0.1524)
				(type default)
			)
			(layer "B.SilkS")
		)
		(fp_line
			(start 0.7874 0.4064)
			(end 0.7874 -0.4064)
			(stroke
				(width 0.1524)
				(type default)
			)
			(layer "B.SilkS")
		)
		(fp_line
			(start -0.7874 -0.4064)
			(end -0.7874 0.4064)
			(stroke
				(width 0.1524)
				(type default)
			)
			(layer "B.SilkS")
		)
		(fp_line
			(start 0.7874 -0.4064)
			(end -0.7874 -0.4064)
			(stroke
				(width 0.1524)
				(type default)
			)
			(layer "B.SilkS")
		)
		(fp_line
			(start -0.67945 0.3048)
			(end -0.120396 0.3048)
			(stroke
				(width 0.1)
				(type default)
			)
			(layer "B.Fab")
		)
		(fp_line
			(start -0.120396 0.3048)
			(end -0.120396 0.2794)
			(stroke
				(width 0.1)
				(type default)
			)
			(layer "B.Fab")
		)
		(fp_line
			(start 0.12065 0.3048)
			(end 0.67945 0.3048)
			(stroke
				(width 0.1)
				(type default)
			)
			(layer "B.Fab")
		)
		(fp_line
			(start 0.67945 0.3048)
			(end 0.67945 -0.305054)
			(stroke
				(width 0.1)
				(type default)
			)
			(layer "B.Fab")
		)
		(fp_line
			(start -0.120396 0.2794)
			(end 0.12065 0.2794)
			(stroke
				(width 0.1)
				(type default)
			)
			(layer "B.Fab")
		)
		(fp_line
			(start 0.12065 0.2794)
			(end 0.12065 0.3048)
			(stroke
				(width 0.1)
				(type default)
			)
			(layer "B.Fab")
		)
		(fp_line
			(start -0.12065 -0.2794)
			(end -0.12065 -0.3048)
			(stroke
				(width 0.1)
				(type default)
			)
			(layer "B.Fab")
		)
		(fp_line
			(start 0.12065 -0.2794)
			(end -0.12065 -0.2794)
			(stroke
				(width 0.1)
				(type default)
			)
			(layer "B.Fab")
		)
		(fp_line
			(start -0.67945 -0.3048)
			(end -0.67945 0.3048)
			(stroke
				(width 0.1)
				(type default)
			)
			(layer "B.Fab")
		)
		(fp_line
			(start -0.12065 -0.3048)
			(end -0.67945 -0.3048)
			(stroke
				(width 0.1)
				(type default)
			)
			(layer "B.Fab")
		)
		(fp_line
			(start 0.12065 -0.305054)
			(end 0.12065 -0.2794)
			(stroke
				(width 0.1)
				(type default)
			)
			(layer "B.Fab")
		)
		(fp_line
			(start 0.67945 -0.305054)
			(end 0.12065 -0.305054)
			(stroke
				(width 0.1)
				(type default)
			)
			(layer "B.Fab")
		)
		(pad "1" smd circle
			(at 0.40005 0 90)
			(size 0 0)
			(layers "B.Cu" "B.Mask" "B.Paste")
			(net "RST_PLD_CPU0_DRAM_CD_N")
		)
		(pad "2" smd circle
			(at -0.40005 0 90)
			(size 0 0)
			(layers "B.Cu" "B.Mask" "B.Paste")
			(net "GND")
		)
	)
	(footprint ""
		(layer "B.Cu")
		(at 243.496084 -397.067024 180)
		(property "Reference" "PR2537"
			(at 0 0 0)
			(layer "B.SilkS")
			(hide yes)
			(effects
				(font
					(size 1.27 1.27)
				)
				(justify mirror)
			)
		)
		(property "Value" ""
			(at 0 0 0)
			(layer "B.Fab")
			(effects
				(font
					(size 1.27 1.27)
				)
				(justify mirror)
			)
		)
		(duplicate_pad_numbers_are_jumpers no)
		(fp_line
			(start 0.7874 0.4064)
			(end 0.7874 -0.4064)
			(stroke
				(width 0.1524)
				(type default)
			)
			(layer "B.SilkS")
		)
		(fp_line
			(start 0.7874 -0.4064)
			(end -0.7874 -0.4064)
			(stroke
				(width 0.1524)
				(type default)
			)
			(layer "B.SilkS")
		)
		(fp_line
			(start -0.7874 0.4064)
			(end 0.7874 0.4064)
			(stroke
				(width 0.1524)
				(type default)
			)
			(layer "B.SilkS")
		)
		(fp_line
			(start -0.7874 -0.4064)
			(end -0.7874 0.4064)
			(stroke
				(width 0.1524)
				(type default)
			)
			(layer "B.SilkS")
		)
		(fp_line
			(start 0.67945 0.3048)
			(end 0.67945 -0.305054)
			(stroke
				(width 0.1)
				(type default)
			)
			(layer "B.Fab")
		)
		(fp_line
			(start 0.67945 -0.305054)
			(end 0.12065 -0.305054)
			(stroke
				(width 0.1)
				(type default)
			)
			(layer "B.Fab")
		)
		(fp_line
			(start 0.12065 0.3048)
			(end 0.67945 0.3048)
			(stroke
				(width 0.1)
				(type default)
			)
			(layer "B.Fab")
		)
		(fp_line
			(start 0.12065 0.2794)
			(end 0.12065 0.3048)
			(stroke
				(width 0.1)
				(type default)
			)
			(layer "B.Fab")
		)
		(fp_line
			(start 0.12065 -0.2794)
			(end -0.12065 -0.2794)
			(stroke
				(width 0.1)
				(type default)
			)
			(layer "B.Fab")
		)
		(fp_line
			(start 0.12065 -0.305054)
			(end 0.12065 -0.2794)
			(stroke
				(width 0.1)
				(type default)
			)
			(layer "B.Fab")
		)
		(fp_line
			(start -0.120396 0.3048)
			(end -0.120396 0.2794)
			(stroke
				(width 0.1)
				(type default)
			)
			(layer "B.Fab")
		)
		(fp_line
			(start -0.120396 0.2794)
			(end 0.12065 0.2794)
			(stroke
				(width 0.1)
				(type default)
			)
			(layer "B.Fab")
		)
		(fp_line
			(start -0.12065 -0.2794)
			(end -0.12065 -0.3048)
			(stroke
				(width 0.1)
				(type default)
			)
			(layer "B.Fab")
		)
		(fp_line
			(start -0.12065 -0.3048)
			(end -0.67945 -0.3048)
			(stroke
				(width 0.1)
				(type default)
			)
			(layer "B.Fab")
		)
		(fp_line
			(start -0.67945 0.3048)
			(end -0.120396 0.3048)
			(stroke
				(width 0.1)
				(type default)
			)
			(layer "B.Fab")
		)
		(fp_line
			(start -0.67945 -0.3048)
			(end -0.67945 0.3048)
			(stroke
				(width 0.1)
				(type default)
			)
			(layer "B.Fab")
		)
		(pad "1" smd circle
			(at 0.40005 0)
			(size 0 0)
			(layers "B.Cu" "B.Mask" "B.Paste")
			(net "P12V_AUX")
		)
		(pad "2" smd circle
			(at -0.40005 0)
			(size 0 0)
			(layers "B.Cu" "B.Mask" "B.Paste")
			(net "P12V_HSC_GATE_RC")
		)
	)
	(footprint ""
		(layer "B.Cu")
		(at 318.262254 -65.048892)
		(property "Reference" "C1184"
			(at 0 0 0)
			(layer "B.SilkS")
			(hide yes)
			(effects
				(font
					(size 1.27 1.27)
				)
				(justify mirror)
			)
		)
		(property "Value" ""
			(at 0 0 0)
			(layer "B.Fab")
			(effects
				(font
					(size 1.27 1.27)
				)
				(justify mirror)
			)
		)
		(duplicate_pad_numbers_are_jumpers no)
		(fp_line
			(start -1.2954 -0.5842)
			(end -1.2954 0.5842)
			(stroke
				(width 0.1524)
				(type default)
			)
			(layer "B.SilkS")
		)
		(fp_line
			(start -1.2954 0.5842)
			(end 1.2954 0.5842)
			(stroke
				(width 0.1524)
				(type default)
			)
			(layer "B.SilkS")
		)
		(fp_line
			(start 0 -0.5842)
			(end 0 0.5842)
			(stroke
				(width 0.1524)
				(type default)
			)
			(layer "B.SilkS")
		)
		(fp_line
			(start 1.2954 -0.5842)
			(end -1.2954 -0.5842)
			(stroke
				(width 0.1524)
				(type default)
			)
			(layer "B.SilkS")
		)
		(fp_line
			(start 1.2954 0.5842)
			(end 1.2954 -0.5842)
			(stroke
				(width 0.1524)
				(type default)
			)
			(layer "B.SilkS")
		)
		(fp_line
			(start -1.1938 -0.4064)
			(end -1.1938 0.4064)
			(stroke
				(width 0.1)
				(type default)
			)
			(layer "B.Fab")
		)
		(fp_line
			(start -1.1938 0.4064)
			(end -0.8636 0.4064)
			(stroke
				(width 0.1)
				(type default)
			)
			(layer "B.Fab")
		)
		(fp_line
			(start -0.8636 -0.4572)
			(end -0.8636 -0.4064)
			(stroke
				(width 0.1)
				(type default)
			)
			(layer "B.Fab")
		)
		(fp_line
			(start -0.8636 -0.4064)
			(end -1.1938 -0.4064)
			(stroke
				(width 0.1)
				(type default)
			)
			(layer "B.Fab")
		)
		(fp_line
			(start -0.8636 0.4064)
			(end -0.8636 0.4572)
			(stroke
				(width 0.1)
				(type default)
			)
			(layer "B.Fab")
		)
		(fp_line
			(start -0.8636 0.4572)
			(end 0.8636 0.4572)
			(stroke
				(width 0.1)
				(type default)
			)
			(layer "B.Fab")
		)
		(fp_line
			(start 0.8636 -0.4572)
			(end -0.8636 -0.4572)
			(stroke
				(width 0.1)
				(type default)
			)
			(layer "B.Fab")
		)
		(fp_line
			(start 0.8636 -0.4064)
			(end 0.8636 -0.4572)
			(stroke
				(width 0.1)
				(type default)
			)
			(layer "B.Fab")
		)
		(fp_line
			(start 0.8636 0.4064)
			(end 1.1938 0.4064)
			(stroke
				(width 0.1)
				(type default)
			)
			(layer "B.Fab")
		)
		(fp_line
			(start 0.8636 0.4572)
			(end 0.8636 0.4064)
			(stroke
				(width 0.1)
				(type default)
			)
			(layer "B.Fab")
		)
		(fp_line
			(start 1.1938 -0.4064)
			(end 0.8636 -0.4064)
			(stroke
				(width 0.1)
				(type default)
			)
			(layer "B.Fab")
		)
		(fp_line
			(start 1.1938 0.4064)
			(end 1.1938 -0.4064)
			(stroke
				(width 0.1)
				(type default)
			)
			(layer "B.Fab")
		)
		(pad "1" smd rect
			(at 0.7366 0 270)
			(size 0.7112 0.8128)
			(layers "B.Cu" "B.Mask" "B.Paste")
			(net "P3V3_AUX")
		)
		(pad "2" smd rect
			(at -0.7366 0 270)
			(size 0.7112 0.8128)
			(layers "B.Cu" "B.Mask" "B.Paste")
			(net "GND")
		)
	)
	(footprint ""
		(layer "B.Cu")
		(at 425.555156 -318.908176 90)
		(property "Reference" "R2733"
			(at 0 0 90)
			(layer "B.SilkS")
			(hide yes)
			(effects
				(font
					(size 1.27 1.27)
				)
				(justify mirror)
			)
		)
		(property "Value" ""
			(at 0 0 90)
			(layer "B.Fab")
			(effects
				(font
					(size 1.27 1.27)
				)
				(justify mirror)
			)
		)
		(duplicate_pad_numbers_are_jumpers no)
		(fp_line
			(start 0.7874 -0.4064)
			(end -0.7874 -0.4064)
			(stroke
				(width 0.1524)
				(type default)
			)
			(layer "B.SilkS")
		)
		(fp_line
			(start -0.7874 -0.4064)
			(end -0.7874 0.4064)
			(stroke
				(width 0.1524)
				(type default)
			)
			(layer "B.SilkS")
		)
		(fp_line
			(start 0.7874 0.4064)
			(end 0.7874 -0.4064)
			(stroke
				(width 0.1524)
				(type default)
			)
			(layer "B.SilkS")
		)
		(fp_line
			(start -0.7874 0.4064)
			(end 0.7874 0.4064)
			(stroke
				(width 0.1524)
				(type default)
			)
			(layer "B.SilkS")
		)
		(fp_line
			(start 0.67945 -0.305054)
			(end 0.12065 -0.305054)
			(stroke
				(width 0.1)
				(type default)
			)
			(layer "B.Fab")
		)
		(fp_line
			(start 0.12065 -0.305054)
			(end 0.12065 -0.2794)
			(stroke
				(width 0.1)
				(type default)
			)
			(layer "B.Fab")
		)
		(fp_line
			(start -0.12065 -0.3048)
			(end -0.67945 -0.3048)
			(stroke
				(width 0.1)
				(type default)
			)
			(layer "B.Fab")
		)
		(fp_line
			(start -0.67945 -0.3048)
			(end -0.67945 0.3048)
			(stroke
				(width 0.1)
				(type default)
			)
			(layer "B.Fab")
		)
		(fp_line
			(start 0.12065 -0.2794)
			(end -0.12065 -0.2794)
			(stroke
				(width 0.1)
				(type default)
			)
			(layer "B.Fab")
		)
		(fp_line
			(start -0.12065 -0.2794)
			(end -0.12065 -0.3048)
			(stroke
				(width 0.1)
				(type default)
			)
			(layer "B.Fab")
		)
		(fp_line
			(start 0.12065 0.2794)
			(end 0.12065 0.3048)
			(stroke
				(width 0.1)
				(type default)
			)
			(layer "B.Fab")
		)
		(fp_line
			(start -0.120396 0.2794)
			(end 0.12065 0.2794)
			(stroke
				(width 0.1)
				(type default)
			)
			(layer "B.Fab")
		)
		(fp_line
			(start 0.67945 0.3048)
			(end 0.67945 -0.305054)
			(stroke
				(width 0.1)
				(type default)
			)
			(layer "B.Fab")
		)
		(fp_line
			(start 0.12065 0.3048)
			(end 0.67945 0.3048)
			(stroke
				(width 0.1)
				(type default)
			)
			(layer "B.Fab")
		)
		(fp_line
			(start -0.120396 0.3048)
			(end -0.120396 0.2794)
			(stroke
				(width 0.1)
				(type default)
			)
			(layer "B.Fab")
		)
		(fp_line
			(start -0.67945 0.3048)
			(end -0.120396 0.3048)
			(stroke
				(width 0.1)
				(type default)
			)
			(layer "B.Fab")
		)
		(pad "1" smd circle
			(at 0.40005 0 270)
			(size 0 0)
			(layers "B.Cu" "B.Mask" "B.Paste")
			(net "PWRGD_CHF_CPU0_DIMM2")
		)
		(pad "2" smd circle
			(at -0.40005 0 270)
			(size 0 0)
			(layers "B.Cu" "B.Mask" "B.Paste")
			(net "PWRGD_FAIL_CPU0_EF")
		)
	)
	(footprint ""
		(layer "B.Cu")
		(at 365.429038 -180.99405)
		(property "Reference" "R1002"
			(at 0 0 0)
			(layer "B.SilkS")
			(hide yes)
			(effects
				(font
					(size 1.27 1.27)
				)
				(justify mirror)
			)
		)
		(property "Value" ""
			(at 0 0 0)
			(layer "B.Fab")
			(effects
				(font
					(size 1.27 1.27)
				)
				(justify mirror)
			)
		)
		(duplicate_pad_numbers_are_jumpers no)
		(fp_line
			(start -0.7874 -0.4064)
			(end -0.7874 0.4064)
			(stroke
				(width 0.1524)
				(type default)
			)
			(layer "B.SilkS")
		)
		(fp_line
			(start -0.7874 0.4064)
			(end 0.7874 0.4064)
			(stroke
				(width 0.1524)
				(type default)
			)
			(layer "B.SilkS")
		)
		(fp_line
			(start 0.7874 -0.4064)
			(end -0.7874 -0.4064)
			(stroke
				(width 0.1524)
				(type default)
			)
			(layer "B.SilkS")
		)
		(fp_line
			(start 0.7874 0.4064)
			(end 0.7874 -0.4064)
			(stroke
				(width 0.1524)
				(type default)
			)
			(layer "B.SilkS")
		)
		(fp_line
			(start -0.67945 -0.3048)
			(end -0.67945 0.3048)
			(stroke
				(width 0.1)
				(type default)
			)
			(layer "B.Fab")
		)
		(fp_line
			(start -0.67945 0.3048)
			(end -0.120396 0.3048)
			(stroke
				(width 0.1)
				(type default)
			)
			(layer "B.Fab")
		)
		(fp_line
			(start -0.12065 -0.3048)
			(end -0.67945 -0.3048)
			(stroke
				(width 0.1)
				(type default)
			)
			(layer "B.Fab")
		)
		(fp_line
			(start -0.12065 -0.2794)
			(end -0.12065 -0.3048)
			(stroke
				(width 0.1)
				(type default)
			)
			(layer "B.Fab")
		)
		(fp_line
			(start -0.120396 0.2794)
			(end 0.12065 0.2794)
			(stroke
				(width 0.1)
				(type default)
			)
			(layer "B.Fab")
		)
		(fp_line
			(start -0.120396 0.3048)
			(end -0.120396 0.2794)
			(stroke
				(width 0.1)
				(type default)
			)
			(layer "B.Fab")
		)
		(fp_line
			(start 0.12065 -0.305054)
			(end 0.12065 -0.2794)
			(stroke
				(width 0.1)
				(type default)
			)
			(layer "B.Fab")
		)
		(fp_line
			(start 0.12065 -0.2794)
			(end -0.12065 -0.2794)
			(stroke
				(width 0.1)
				(type default)
			)
			(layer "B.Fab")
		)
		(fp_line
			(start 0.12065 0.2794)
			(end 0.12065 0.3048)
			(stroke
				(width 0.1)
				(type default)
			)
			(layer "B.Fab")
		)
		(fp_line
			(start 0.12065 0.3048)
			(end 0.67945 0.3048)
			(stroke
				(width 0.1)
				(type default)
			)
			(layer "B.Fab")
		)
		(fp_line
			(start 0.67945 -0.305054)
			(end 0.12065 -0.305054)
			(stroke
				(width 0.1)
				(type default)
			)
			(layer "B.Fab")
		)
		(fp_line
			(start 0.67945 0.3048)
			(end 0.67945 -0.305054)
			(stroke
				(width 0.1)
				(type default)
			)
			(layer "B.Fab")
		)
		(pad "1" smd circle
			(at 0.40005 0 180)
			(size 0 0)
			(layers "B.Cu" "B.Mask" "B.Paste")
			(net "P3V3")
		)
		(pad "2" smd circle
			(at -0.40005 0 180)
			(size 0 0)
			(layers "B.Cu" "B.Mask" "B.Paste")
			(net "FM_SMB_CPU0_ALERT_R1")
		)
	)
	(footprint ""
		(layer "B.Cu")
		(at 117.904514 -336.192368 -90)
		(property "Reference" "PR301"
			(at 0 0 90)
			(layer "B.SilkS")
			(hide yes)
			(effects
				(font
					(size 1.27 1.27)
				)
				(justify mirror)
			)
		)
		(property "Value" ""
			(at 0 0 90)
			(layer "B.Fab")
			(effects
				(font
					(size 1.27 1.27)
				)
				(justify mirror)
			)
		)
		(duplicate_pad_numbers_are_jumpers no)
		(fp_line
			(start -0.7874 0.4064)
			(end 0.7874 0.4064)
			(stroke
				(width 0.1524)
				(type default)
			)
			(layer "B.SilkS")
		)
		(fp_line
			(start 0.7874 0.4064)
			(end 0.7874 -0.4064)
			(stroke
				(width 0.1524)
				(type default)
			)
			(layer "B.SilkS")
		)
		(fp_line
			(start -0.7874 -0.4064)
			(end -0.7874 0.4064)
			(stroke
				(width 0.1524)
				(type default)
			)
			(layer "B.SilkS")
		)
		(fp_line
			(start 0.7874 -0.4064)
			(end -0.7874 -0.4064)
			(stroke
				(width 0.1524)
				(type default)
			)
			(layer "B.SilkS")
		)
		(fp_line
			(start -0.67945 0.3048)
			(end -0.120396 0.3048)
			(stroke
				(width 0.1)
				(type default)
			)
			(layer "B.Fab")
		)
		(fp_line
			(start -0.120396 0.3048)
			(end -0.120396 0.2794)
			(stroke
				(width 0.1)
				(type default)
			)
			(layer "B.Fab")
		)
		(fp_line
			(start 0.12065 0.3048)
			(end 0.67945 0.3048)
			(stroke
				(width 0.1)
				(type default)
			)
			(layer "B.Fab")
		)
		(fp_line
			(start 0.67945 0.3048)
			(end 0.67945 -0.305054)
			(stroke
				(width 0.1)
				(type default)
			)
			(layer "B.Fab")
		)
		(fp_line
			(start -0.120396 0.2794)
			(end 0.12065 0.2794)
			(stroke
				(width 0.1)
				(type default)
			)
			(layer "B.Fab")
		)
		(fp_line
			(start 0.12065 0.2794)
			(end 0.12065 0.3048)
			(stroke
				(width 0.1)
				(type default)
			)
			(layer "B.Fab")
		)
		(fp_line
			(start -0.12065 -0.2794)
			(end -0.12065 -0.3048)
			(stroke
				(width 0.1)
				(type default)
			)
			(layer "B.Fab")
		)
		(fp_line
			(start 0.12065 -0.2794)
			(end -0.12065 -0.2794)
			(stroke
				(width 0.1)
				(type default)
			)
			(layer "B.Fab")
		)
		(fp_line
			(start -0.67945 -0.3048)
			(end -0.67945 0.3048)
			(stroke
				(width 0.1)
				(type default)
			)
			(layer "B.Fab")
		)
		(fp_line
			(start -0.12065 -0.3048)
			(end -0.67945 -0.3048)
			(stroke
				(width 0.1)
				(type default)
			)
			(layer "B.Fab")
		)
		(fp_line
			(start 0.12065 -0.305054)
			(end 0.12065 -0.2794)
			(stroke
				(width 0.1)
				(type default)
			)
			(layer "B.Fab")
		)
		(fp_line
			(start 0.67945 -0.305054)
			(end 0.12065 -0.305054)
			(stroke
				(width 0.1)
				(type default)
			)
			(layer "B.Fab")
		)
		(pad "1" smd circle
			(at 0.40005 0 90)
			(size 0 0)
			(layers "B.Cu" "B.Mask" "B.Paste")
			(net "PVCCIN_CPU1_VOS4")
		)
		(pad "2" smd circle
			(at -0.40005 0 90)
			(size 0 0)
			(layers "B.Cu" "B.Mask" "B.Paste")
			(net "PVCCIN_CPU1")
		)
	)
)
